# T6G (Grand Teton) — schematic netlist excerpt (pin names and nets, part order shuffled) for the footprints in the layout excerpt that follows; sources: Cadence DE-HDL packaged netlist, KiCad conversion of 04192023_DAF0TMB3IC0_F0TG_MB_C_brd_V02_OCP.brd

PC2212  Q_CAP  1UF 25V 10% X6S  pkg C0402  page 146 : A = GND ; B = P3V3_E1S_REG_0
R1636  Q_RES  22 1% CHIP  pkg 0402LF  page 172 : A = JTAG_DBREQ_R_N ; B = JTAG_DBREQ_N

(kicad_pcb
	(version 20260206)
	(generator "pcbnew")
	(generator_version "10.0")
	(general
		(thickness 1.6)
		(legacy_teardrops no)
	)
	(paper "A4")
	(title_block
		(title "04192023_DAF0TMB3IC0_F0TG_MB_C_brd_V02_OCP.brd")
		(comment 1 "Grand Teton / footprints 828-829 of 8354")
	)
	(layers
		(0 "F.Cu" signal "TOP")
		(4 "In1.Cu" signal "GND")
		(6 "In2.Cu" signal "IN1")
		(8 "In3.Cu" signal "GND1")
		(10 "In4.Cu" signal "IN2")
		(12 "In5.Cu" signal "GND2")
		(14 "In6.Cu" signal "IN3")
		(16 "In7.Cu" signal "GND3")
		(18 "In8.Cu" signal "VCC")
		(20 "In9.Cu" signal "VCC1")
		(22 "In10.Cu" signal "GND4")
		(24 "In11.Cu" signal "IN4")
		(26 "In12.Cu" signal "GND5")
		(28 "In13.Cu" signal "IN5")
		(30 "In14.Cu" signal "GND6")
		(32 "In15.Cu" signal "IN6")
		(34 "In16.Cu" signal "GND7")
		(2 "B.Cu" signal "BOTTOM")
		(9 "F.Adhes" user "F.Adhesive")
		(11 "B.Adhes" user "B.Adhesive")
		(13 "F.Paste" user "Package Geometry/Pastemask Top")
		(15 "B.Paste" user "Package Geometry/Pastemask Bottom")
		(5 "F.SilkS" user "Ref Des/Silkscreen Top")
		(7 "B.SilkS" user "Ref Des/Silkscreen Bottom")
		(1 "F.Mask" user "Board Geometry/Soldermask Top")
		(3 "B.Mask" user "Board Geometry/Soldermask Bottom")
		(17 "Dwgs.User" user "User.Drawings")
		(19 "Cmts.User" user "User.Comments")
		(21 "Eco1.User" user "User.Eco1")
		(23 "Eco2.User" user "User.Eco2")
		(25 "Edge.Cuts" user "Board Geometry/Outline")
		(27 "Margin" user)
		(31 "F.CrtYd" user "Package Geometry/Place Bound Top")
		(29 "B.CrtYd" user "Package Geometry/Place Bound Bottom")
		(35 "F.Fab" user "Ref Des/Assembly Top")
		(33 "B.Fab" user "Ref Des/Assembly Bottom")
	)
	(footprint ""
		(layer "F.Cu")
		(at 217.889582 -69.397118)
		(property "Reference" "PC2212"
			(at 0 0 0)
			(layer "F.SilkS")
			(hide yes)
			(effects
				(font
					(size 1.27 1.27)
				)
			)
		)
		(property "Value" ""
			(at 0 0 0)
			(layer "F.Fab")
			(effects
				(font
					(size 1.27 1.27)
				)
			)
		)
		(duplicate_pad_numbers_are_jumpers no)
		(fp_line
			(start -0.7874 -0.4064)
			(end 0.7874 -0.4064)
			(stroke
				(width 0.1524)
				(type default)
			)
			(layer "F.SilkS")
		)
		(fp_line
			(start -0.7874 0.4064)
			(end -0.7874 -0.4064)
			(stroke
				(width 0.1524)
				(type default)
			)
			(layer "F.SilkS")
		)
		(fp_line
			(start 0.7874 -0.4064)
			(end 0.7874 0.4064)
			(stroke
				(width 0.1524)
				(type default)
			)
			(layer "F.SilkS")
		)
		(fp_line
			(start 0.7874 0.4064)
			(end -0.7874 0.4064)
			(stroke
				(width 0.1524)
				(type default)
			)
			(layer "F.SilkS")
		)
		(fp_line
			(start -0.67945 -0.305054)
			(end -0.12065 -0.305054)
			(stroke
				(width 0.1)
				(type default)
			)
			(layer "F.Fab")
		)
		(fp_line
			(start -0.67945 0.3048)
			(end -0.67945 -0.305054)
			(stroke
				(width 0.1)
				(type default)
			)
			(layer "F.Fab")
		)
		(fp_line
			(start -0.12065 -0.305054)
			(end -0.12065 -0.2794)
			(stroke
				(width 0.1)
				(type default)
			)
			(layer "F.Fab")
		)
		(fp_line
			(start -0.12065 -0.2794)
			(end 0.12065 -0.2794)
			(stroke
				(width 0.1)
				(type default)
			)
			(layer "F.Fab")
		)
		(fp_line
			(start -0.12065 0.2794)
			(end -0.12065 0.3048)
			(stroke
				(width 0.1)
				(type default)
			)
			(layer "F.Fab")
		)
		(fp_line
			(start -0.12065 0.3048)
			(end -0.67945 0.3048)
			(stroke
				(width 0.1)
				(type default)
			)
			(layer "F.Fab")
		)
		(fp_line
			(start 0.120396 0.2794)
			(end -0.12065 0.2794)
			(stroke
				(width 0.1)
				(type default)
			)
			(layer "F.Fab")
		)
		(fp_line
			(start 0.120396 0.3048)
			(end 0.120396 0.2794)
			(stroke
				(width 0.1)
				(type default)
			)
			(layer "F.Fab")
		)
		(fp_line
			(start 0.12065 -0.3048)
			(end 0.67945 -0.3048)
			(stroke
				(width 0.1)
				(type default)
			)
			(layer "F.Fab")
		)
		(fp_line
			(start 0.12065 -0.2794)
			(end 0.12065 -0.3048)
			(stroke
				(width 0.1)
				(type default)
			)
			(layer "F.Fab")
		)
		(fp_line
			(start 0.67945 -0.3048)
			(end 0.67945 0.3048)
			(stroke
				(width 0.1)
				(type default)
			)
			(layer "F.Fab")
		)
		(fp_line
			(start 0.67945 0.3048)
			(end 0.120396 0.3048)
			(stroke
				(width 0.1)
				(type default)
			)
			(layer "F.Fab")
		)
		(pad "1" smd circle
			(at -0.40005 0)
			(size 0 0)
			(layers "F.Cu" "F.Mask" "F.Paste")
			(net "GND")
		)
		(pad "2" smd circle
			(at 0.40005 0)
			(size 0 0)
			(layers "F.Cu" "F.Mask" "F.Paste")
			(net "P3V3_E1S_REG_0")
		)
	)
	(footprint ""
		(layer "F.Cu")
		(at 259.834126 -100.016056 180)
		(property "Reference" "R1636"
			(at 0 0 180)
			(layer "F.SilkS")
			(hide yes)
			(effects
				(font
					(size 1.27 1.27)
				)
			)
		)
		(property "Value" ""
			(at 0 0 180)
			(layer "F.Fab")
			(effects
				(font
					(size 1.27 1.27)
				)
			)
		)
		(duplicate_pad_numbers_are_jumpers no)
		(fp_line
			(start 0.7874 0.4064)
			(end -0.7874 0.4064)
			(stroke
				(width 0.1524)
				(type default)
			)
			(layer "F.SilkS")
		)
		(fp_line
			(start 0.7874 -0.4064)
			(end 0.7874 0.4064)
			(stroke
				(width 0.1524)
				(type default)
			)
			(layer "F.SilkS")
		)
		(fp_line
			(start -0.7874 0.4064)
			(end -0.7874 -0.4064)
			(stroke
				(width 0.1524)
				(type default)
			)
			(layer "F.SilkS")
		)
		(fp_line
			(start -0.7874 -0.4064)
			(end 0.7874 -0.4064)
			(stroke
				(width 0.1524)
				(type default)
			)
			(layer "F.SilkS")
		)
		(fp_line
			(start 0.67945 0.3048)
			(end 0.120396 0.3048)
			(stroke
				(width 0.1)
				(type default)
			)
			(layer "F.Fab")
		)
		(fp_line
			(start 0.67945 -0.3048)
			(end 0.67945 0.3048)
			(stroke
				(width 0.1)
				(type default)
			)
			(layer "F.Fab")
		)
		(fp_line
			(start 0.12065 -0.2794)
			(end 0.12065 -0.3048)
			(stroke
				(width 0.1)
				(type default)
			)
			(layer "F.Fab")
		)
		(fp_line
			(start 0.12065 -0.3048)
			(end 0.67945 -0.3048)
			(stroke
				(width 0.1)
				(type default)
			)
			(layer "F.Fab")
		)
		(fp_line
			(start 0.120396 0.3048)
			(end 0.120396 0.2794)
			(stroke
				(width 0.1)
				(type default)
			)
			(layer "F.Fab")
		)
		(fp_line
			(start 0.120396 0.2794)
			(end -0.12065 0.2794)
			(stroke
				(width 0.1)
				(type default)
			)
			(layer "F.Fab")
		)
		(fp_line
			(start -0.12065 0.3048)
			(end -0.67945 0.3048)
			(stroke
				(width 0.1)
				(type default)
			)
			(layer "F.Fab")
		)
		(fp_line
			(start -0.12065 0.2794)
			(end -0.12065 0.3048)
			(stroke
				(width 0.1)
				(type default)
			)
			(layer "F.Fab")
		)
		(fp_line
			(start -0.12065 -0.2794)
			(end 0.12065 -0.2794)
			(stroke
				(width 0.1)
				(type default)
			)
			(layer "F.Fab")
		)
		(fp_line
			(start -0.12065 -0.305054)
			(end -0.12065 -0.2794)
			(stroke
				(width 0.1)
				(type default)
			)
			(layer "F.Fab")
		)
		(fp_line
			(start -0.67945 0.3048)
			(end -0.67945 -0.305054)
			(stroke
				(width 0.1)
				(type default)
			)
			(layer "F.Fab")
		)
		(fp_line
			(start -0.67945 -0.305054)
			(end -0.12065 -0.305054)
			(stroke
				(width 0.1)
				(type default)
			)
			(layer "F.Fab")
		)
		(pad "1" smd circle
			(at -0.40005 0 180)
			(size 0 0)
			(layers "F.Cu" "F.Mask" "F.Paste")
			(net "JTAG_DBREQ_R_N")
		)
		(pad "2" smd circle
			(at 0.40005 0 180)
			(size 0 0)
			(layers "F.Cu" "F.Mask" "F.Paste")
			(net "JTAG_DBREQ_N")
		)
	)
)
